(kicad_pcb
	(version 20241229)
	(generator "pcbnew")
	(generator_version "9.0")
	(general
		(thickness 1.599998)
		(legacy_teardrops no)
	)
	(paper "A4")
	(title_block
		(title "Artix - Datacenter Secure Control Module (DC-SCM)")
		(date "2024-11-06")
		(rev "1.1.3")
		(comment 9 "footprints 329-333 of 544")
	)
	(layers
		(0 "F.Cu" signal)
		(4 "In1.Cu" signal)
		(6 "In2.Cu" signal)
		(8 "In3.Cu" signal)
		(10 "In4.Cu" signal)
		(12 "In5.Cu" signal)
		(14 "In6.Cu" signal)
		(2 "B.Cu" signal)
		(9 "F.Adhes" user "F.Adhesive")
		(11 "B.Adhes" user "B.Adhesive")
		(13 "F.Paste" user)
		(15 "B.Paste" user)
		(5 "F.SilkS" user "F.Silkscreen")
		(7 "B.SilkS" user "B.Silkscreen")
		(1 "F.Mask" user)
		(3 "B.Mask" user)
		(17 "Dwgs.User" user "User.Drawings")
		(19 "Cmts.User" user "User.Comments")
		(21 "Eco1.User" user "User.Eco1")
		(23 "Eco2.User" user "User.Eco2")
		(25 "Edge.Cuts" user)
		(27 "Margin" user)
		(31 "F.CrtYd" user "F.Courtyard")
		(29 "B.CrtYd" user "B.Courtyard")
		(35 "F.Fab" user)
		(33 "B.Fab" user)
	)
	(footprint "antmicro-footprints:R_0402_1005Metric"
		(layer "B.Cu")
		(at 75.575 158.475 90)
		(descr "Resistor SMD 0402")
		(tags "resistor SMD 0402")
		(property "Reference" "R135"
			(at -3.625 0.425 90)
			(layer "B.SilkS")
			(effects
				(font
					(size 0.7 0.7)
					(thickness 0.15)
				)
				(justify right bottom mirror)
			)
		)
		(property "Value" "R_4k7_0402"
			(at 0 -1.4 90)
			(layer "B.Fab")
			(effects
				(font
					(size 0.7 0.7)
					(thickness 0.15)
				)
				(justify right bottom mirror)
			)
		)
		(property "Datasheet" "https://www.bourns.com/docs/product-datasheets/cr.pdf"
			(at 0 0 90)
			(layer "F.Fab")
			(hide yes)
			(effects
				(font
					(size 1.27 1.27)
					(thickness 0.15)
				)
			)
		)
		(property "Description" "SMD Chip Resistor, 4.7 kohm, ± 1%, 62.5 mW, 0402 [1005 Metric], Thick Film, General Purpose"
			(at 0 0 90)
			(layer "F.Fab")
			(hide yes)
			(effects
				(font
					(size 1.27 1.27)
					(thickness 0.15)
				)
			)
		)
		(property "Author" "Antmicro"
			(at 234.05 82.9 0)
			(layer "B.Fab")
			(hide yes)
			(effects
				(font
					(size 1 1)
					(thickness 0.15)
				)
				(justify mirror)
			)
		)
		(property "License" "Apache-2.0"
			(at 234.05 82.9 0)
			(layer "B.Fab")
			(hide yes)
			(effects
				(font
					(size 1 1)
					(thickness 0.15)
				)
				(justify mirror)
			)
		)
		(property "MPN" "CR0402-FX-4701GLF"
			(at 234.05 82.9 0)
			(layer "B.Fab")
			(hide yes)
			(effects
				(font
					(size 1 1)
					(thickness 0.15)
				)
				(justify mirror)
			)
		)
		(property "Manufacturer" "Bourns"
			(at 234.05 82.9 0)
			(layer "B.Fab")
			(hide yes)
			(effects
				(font
					(size 1 1)
					(thickness 0.15)
				)
				(justify mirror)
			)
		)
		(property "Tolerance" "1%"
			(at 234.05 82.9 0)
			(layer "B.Fab")
			(hide yes)
			(effects
				(font
					(size 1 1)
					(thickness 0.15)
				)
				(justify mirror)
			)
		)
		(property "Val" "4k7"
			(at 234.05 82.9 0)
			(layer "B.Fab")
			(hide yes)
			(effects
				(font
					(size 1 1)
					(thickness 0.15)
				)
				(justify mirror)
			)
		)
		(property "DNP" ""
			(at 0 0 90)
			(unlocked yes)
			(layer "B.Fab")
			(hide yes)
			(effects
				(font
					(size 1 1)
					(thickness 0.15)
				)
				(justify mirror)
			)
		)
		(sheetname "/FPGA banks 13-16/")
		(sheetfile "fpga-banks-13-16.kicad_sch")
		(attr smd)
		(fp_rect
			(start -0.925 0.47)
			(end 0.925 -0.47)
			(stroke
				(width 0.05)
				(type default)
			)
			(fill no)
			(layer "B.CrtYd")
		)
		(fp_rect
			(start -0.5 0.25)
			(end 0.5 -0.25)
			(stroke
				(width 0.15)
				(type solid)
			)
			(fill no)
			(layer "B.Fab")
		)
		(pad "1" smd roundrect
			(at -0.48 0 90)
			(size 0.59 0.64)
			(layers "B.Cu" "B.Mask" "B.Paste")
			(roundrect_rratio 0.25)
			(net 2 "VCC3V3")
			(pintype "passive")
		)
		(pad "2" smd roundrect
			(at 0.48 0 90)
			(size 0.59 0.64)
			(layers "B.Cu" "B.Mask" "B.Paste")
			(roundrect_rratio 0.25)
			(net 333 "ROT_QSPI_DQ3")
			(pintype "passive")
		)
	)
	(footprint "antmicro-footprints:C_0402_1005Metric"
		(layer "B.Cu")
		(at 101.775 127.025 180)
		(descr "Capacitor SMD 0402")
		(tags "capacitor SMD 0402")
		(property "Reference" "C114"
			(at -1.325 -1.275 0)
			(layer "B.SilkS")
			(effects
				(font
					(size 0.7 0.7)
					(thickness 0.15)
				)
				(justify left bottom mirror)
			)
		)
		(property "Value" "C_470n_0402"
			(at 0 -1.4 0)
			(layer "B.Fab")
			(effects
				(font
					(size 0.7 0.7)
					(thickness 0.15)
				)
				(justify left bottom mirror)
			)
		)
		(property "Datasheet" "https://product.tdk.com/en/search/capacitor/ceramic/mlcc/info?part_no=C1005X5R1E474M050BB"
			(at 0 0 180)
			(layer "F.Fab")
			(hide yes)
			(effects
				(font
					(size 1.27 1.27)
					(thickness 0.15)
				)
			)
		)
		(property "Description" "SMD Multilayer Ceramic Capacitor, 0.47 µF, 25 V, 0402 [1005 Metric], ± 20%, X5R, C"
			(at 0 0 180)
			(layer "F.Fab")
			(hide yes)
			(effects
				(font
					(size 1.27 1.27)
					(thickness 0.15)
				)
			)
		)
		(property "Author" "Antmicro"
			(at 203.55 254.05 0)
			(layer "B.Fab")
			(hide yes)
			(effects
				(font
					(size 1 1)
					(thickness 0.15)
				)
				(justify mirror)
			)
		)
		(property "Dielectric" ""
			(at 203.55 254.05 0)
			(layer "B.Fab")
			(hide yes)
			(effects
				(font
					(size 1 1)
					(thickness 0.15)
				)
				(justify mirror)
			)
		)
		(property "License" "Apache-2.0"
			(at 203.55 254.05 0)
			(layer "B.Fab")
			(hide yes)
			(effects
				(font
					(size 1 1)
					(thickness 0.15)
				)
				(justify mirror)
			)
		)
		(property "MPN" "C1005X5R1E474M050BB"
			(at 203.55 254.05 0)
			(layer "B.Fab")
			(hide yes)
			(effects
				(font
					(size 1 1)
					(thickness 0.15)
				)
				(justify mirror)
			)
		)
		(property "Manufacturer" "TDK"
			(at 203.55 254.05 0)
			(layer "B.Fab")
			(hide yes)
			(effects
				(font
					(size 1 1)
					(thickness 0.15)
				)
				(justify mirror)
			)
		)
		(property "Val" "470n"
			(at 203.55 254.05 0)
			(layer "B.Fab")
			(hide yes)
			(effects
				(font
					(size 1 1)
					(thickness 0.15)
				)
				(justify mirror)
			)
		)
		(property "Voltage" ""
			(at 203.55 254.05 0)
			(layer "B.Fab")
			(hide yes)
			(effects
				(font
					(size 1 1)
					(thickness 0.15)
				)
				(justify mirror)
			)
		)
		(property "DNP" ""
			(at 0 0 180)
			(unlocked yes)
			(layer "B.Fab")
			(hide yes)
			(effects
				(font
					(size 1 1)
					(thickness 0.15)
				)
				(justify mirror)
			)
		)
		(sheetname "/FPGA banks 34-35 & CFG/")
		(sheetfile "fpga-banks-34-25-cfg.kicad_sch")
		(attr smd)
		(fp_rect
			(start -0.925 0.47)
			(end 0.925 -0.47)
			(stroke
				(width 0.05)
				(type default)
			)
			(fill no)
			(layer "B.CrtYd")
		)
		(fp_line
			(start 0.504 0.25)
			(end 0.504 -0.248)
			(stroke
				(width 0.15)
				(type solid)
			)
			(layer "B.Fab")
		)
		(fp_line
			(start 0.504 -0.248)
			(end -0.494 -0.248)
			(stroke
				(width 0.15)
				(type solid)
			)
			(layer "B.Fab")
		)
		(fp_line
			(start -0.494 0.25)
			(end 0.504 0.25)
			(stroke
				(width 0.15)
				(type solid)
			)
			(layer "B.Fab")
		)
		(fp_line
			(start -0.494 -0.248)
			(end -0.494 0.25)
			(stroke
				(width 0.15)
				(type solid)
			)
			(layer "B.Fab")
		)
		(pad "1" smd roundrect
			(at -0.48 0 180)
			(size 0.59 0.64)
			(layers "B.Cu" "B.Mask" "B.Paste")
			(roundrect_rratio 0.25)
			(net 1 "GND")
			(pintype "passive")
		)
		(pad "2" smd roundrect
			(at 0.48 0 180)
			(size 0.59 0.64)
			(layers "B.Cu" "B.Mask" "B.Paste")
			(roundrect_rratio 0.25)
			(net 3 "VCC1V35")
			(pintype "passive")
		)
	)
	(footprint "antmicro-footprints:C_0402_1005Metric"
		(layer "B.Cu")
		(at 95.225 128.425 -90)
		(descr "Capacitor SMD 0402")
		(tags "capacitor SMD 0402")
		(property "Reference" "C120"
			(at -1.025 0.525 90)
			(layer "B.SilkS")
			(effects
				(font
					(size 0.7 0.7)
					(thickness 0.15)
				)
				(justify left bottom mirror)
			)
		)
		(property "Value" "C_470n_0402"
			(at 0 -1.4 90)
			(layer "B.Fab")
			(effects
				(font
					(size 0.7 0.7)
					(thickness 0.15)
				)
				(justify left bottom mirror)
			)
		)
		(property "Datasheet" "https://product.tdk.com/en/search/capacitor/ceramic/mlcc/info?part_no=C1005X5R1E474M050BB"
			(at 0 0 270)
			(layer "F.Fab")
			(hide yes)
			(effects
				(font
					(size 1.27 1.27)
					(thickness 0.15)
				)
			)
		)
		(property "Description" "SMD Multilayer Ceramic Capacitor, 0.47 µF, 25 V, 0402 [1005 Metric], ± 20%, X5R, C"
			(at 0 0 270)
			(layer "F.Fab")
			(hide yes)
			(effects
				(font
					(size 1.27 1.27)
					(thickness 0.15)
				)
			)
		)
		(property "Author" "Antmicro"
			(at -33.2 223.65 0)
			(layer "B.Fab")
			(hide yes)
			(effects
				(font
					(size 1 1)
					(thickness 0.15)
				)
				(justify mirror)
			)
		)
		(property "Dielectric" ""
			(at -33.2 223.65 0)
			(layer "B.Fab")
			(hide yes)
			(effects
				(font
					(size 1 1)
					(thickness 0.15)
				)
				(justify mirror)
			)
		)
		(property "License" "Apache-2.0"
			(at -33.2 223.65 0)
			(layer "B.Fab")
			(hide yes)
			(effects
				(font
					(size 1 1)
					(thickness 0.15)
				)
				(justify mirror)
			)
		)
		(property "MPN" "C1005X5R1E474M050BB"
			(at -33.2 223.65 0)
			(layer "B.Fab")
			(hide yes)
			(effects
				(font
					(size 1 1)
					(thickness 0.15)
				)
				(justify mirror)
			)
		)
		(property "Manufacturer" "TDK"
			(at -33.2 223.65 0)
			(layer "B.Fab")
			(hide yes)
			(effects
				(font
					(size 1 1)
					(thickness 0.15)
				)
				(justify mirror)
			)
		)
		(property "Val" "470n"
			(at -33.2 223.65 0)
			(layer "B.Fab")
			(hide yes)
			(effects
				(font
					(size 1 1)
					(thickness 0.15)
				)
				(justify mirror)
			)
		)
		(property "Voltage" ""
			(at -33.2 223.65 0)
			(layer "B.Fab")
			(hide yes)
			(effects
				(font
					(size 1 1)
					(thickness 0.15)
				)
				(justify mirror)
			)
		)
		(property "DNP" ""
			(at 0 0 270)
			(unlocked yes)
			(layer "B.Fab")
			(hide yes)
			(effects
				(font
					(size 1 1)
					(thickness 0.15)
				)
				(justify mirror)
			)
		)
		(sheetname "/FPGA banks 34-35 & CFG/")
		(sheetfile "fpga-banks-34-25-cfg.kicad_sch")
		(attr smd)
		(fp_rect
			(start -0.925 0.47)
			(end 0.925 -0.47)
			(stroke
				(width 0.05)
				(type default)
			)
			(fill no)
			(layer "B.CrtYd")
		)
		(fp_line
			(start -0.494 0.25)
			(end 0.504 0.25)
			(stroke
				(width 0.15)
				(type solid)
			)
			(layer "B.Fab")
		)
		(fp_line
			(start 0.504 0.25)
			(end 0.504 -0.248)
			(stroke
				(width 0.15)
				(type solid)
			)
			(layer "B.Fab")
		)
		(fp_line
			(start -0.494 -0.248)
			(end -0.494 0.25)
			(stroke
				(width 0.15)
				(type solid)
			)
			(layer "B.Fab")
		)
		(fp_line
			(start 0.504 -0.248)
			(end -0.494 -0.248)
			(stroke
				(width 0.15)
				(type solid)
			)
			(layer "B.Fab")
		)
		(pad "1" smd roundrect
			(at -0.48 0 270)
			(size 0.59 0.64)
			(layers "B.Cu" "B.Mask" "B.Paste")
			(roundrect_rratio 0.25)
			(net 1 "GND")
			(pintype "passive")
		)
		(pad "2" smd roundrect
			(at 0.48 0 270)
			(size 0.59 0.64)
			(layers "B.Cu" "B.Mask" "B.Paste")
			(roundrect_rratio 0.25)
			(net 3 "VCC1V35")
			(pintype "passive")
		)
	)
	(footprint "antmicro-footprints:C_0402_1005Metric"
		(layer "B.Cu")
		(at 96.825 126.575)
		(descr "Capacitor SMD 0402")
		(tags "capacitor SMD 0402")
		(property "Reference" "C126"
			(at -1.625 -0.475 0)
			(layer "B.SilkS")
			(effects
				(font
					(size 0.7 0.7)
					(thickness 0.15)
				)
				(justify right bottom mirror)
			)
		)
		(property "Value" "C_470n_0402"
			(at 0 -1.4 0)
			(layer "B.Fab")
			(effects
				(font
					(size 0.7 0.7)
					(thickness 0.15)
				)
				(justify right bottom mirror)
			)
		)
		(property "Datasheet" "https://product.tdk.com/en/search/capacitor/ceramic/mlcc/info?part_no=C1005X5R1E474M050BB"
			(at 0 0 0)
			(layer "F.Fab")
			(hide yes)
			(effects
				(font
					(size 1.27 1.27)
					(thickness 0.15)
				)
			)
		)
		(property "Description" "SMD Multilayer Ceramic Capacitor, 0.47 µF, 25 V, 0402 [1005 Metric], ± 20%, X5R, C"
			(at 0 0 0)
			(layer "F.Fab")
			(hide yes)
			(effects
				(font
					(size 1.27 1.27)
					(thickness 0.15)
				)
			)
		)
		(property "Author" "Antmicro"
			(at 0 0 0)
			(layer "B.Fab")
			(hide yes)
			(effects
				(font
					(size 1 1)
					(thickness 0.15)
				)
				(justify mirror)
			)
		)
		(property "Dielectric" ""
			(at 0 0 0)
			(layer "B.Fab")
			(hide yes)
			(effects
				(font
					(size 1 1)
					(thickness 0.15)
				)
				(justify mirror)
			)
		)
		(property "License" "Apache-2.0"
			(at 0 0 0)
			(layer "B.Fab")
			(hide yes)
			(effects
				(font
					(size 1 1)
					(thickness 0.15)
				)
				(justify mirror)
			)
		)
		(property "MPN" "C1005X5R1E474M050BB"
			(at 0 0 0)
			(layer "B.Fab")
			(hide yes)
			(effects
				(font
					(size 1 1)
					(thickness 0.15)
				)
				(justify mirror)
			)
		)
		(property "Manufacturer" "TDK"
			(at 0 0 0)
			(layer "B.Fab")
			(hide yes)
			(effects
				(font
					(size 1 1)
					(thickness 0.15)
				)
				(justify mirror)
			)
		)
		(property "Val" "470n"
			(at 0 0 0)
			(layer "B.Fab")
			(hide yes)
			(effects
				(font
					(size 1 1)
					(thickness 0.15)
				)
				(justify mirror)
			)
		)
		(property "Voltage" ""
			(at 0 0 0)
			(layer "B.Fab")
			(hide yes)
			(effects
				(font
					(size 1 1)
					(thickness 0.15)
				)
				(justify mirror)
			)
		)
		(property "DNP" ""
			(at 0 0 0)
			(unlocked yes)
			(layer "B.Fab")
			(hide yes)
			(effects
				(font
					(size 1 1)
					(thickness 0.15)
				)
				(justify mirror)
			)
		)
		(sheetname "/FPGA banks 34-35 & CFG/")
		(sheetfile "fpga-banks-34-25-cfg.kicad_sch")
		(attr smd)
		(fp_rect
			(start -0.925 0.47)
			(end 0.925 -0.47)
			(stroke
				(width 0.05)
				(type default)
			)
			(fill no)
			(layer "B.CrtYd")
		)
		(fp_line
			(start -0.494 -0.248)
			(end -0.494 0.25)
			(stroke
				(width 0.15)
				(type solid)
			)
			(layer "B.Fab")
		)
		(fp_line
			(start -0.494 0.25)
			(end 0.504 0.25)
			(stroke
				(width 0.15)
				(type solid)
			)
			(layer "B.Fab")
		)
		(fp_line
			(start 0.504 -0.248)
			(end -0.494 -0.248)
			(stroke
				(width 0.15)
				(type solid)
			)
			(layer "B.Fab")
		)
		(fp_line
			(start 0.504 0.25)
			(end 0.504 -0.248)
			(stroke
				(width 0.15)
				(type solid)
			)
			(layer "B.Fab")
		)
		(pad "1" smd roundrect
			(at -0.48 0)
			(size 0.59 0.64)
			(layers "B.Cu" "B.Mask" "B.Paste")
			(roundrect_rratio 0.25)
			(net 1 "GND")
			(pintype "passive")
		)
		(pad "2" smd roundrect
			(at 0.48 0)
			(size 0.59 0.64)
			(layers "B.Cu" "B.Mask" "B.Paste")
			(roundrect_rratio 0.25)
			(net 3 "VCC1V35")
			(pintype "passive")
		)
	)
	(footprint "antmicro-footprints:C_0402_1005Metric"
		(layer "B.Cu")
		(at 93.025 129.125 -90)
		(descr "Capacitor SMD 0402")
		(tags "capacitor SMD 0402")
		(property "Reference" "C132"
			(at -1.025 0.525 90)
			(layer "B.SilkS")
			(effects
				(font
					(size 0.7 0.7)
					(thickness 0.15)
				)
				(justify left bottom mirror)
			)
		)
		(property "Value" "C_470n_0402"
			(at 0 -1.4 90)
			(layer "B.Fab")
			(effects
				(font
					(size 0.7 0.7)
					(thickness 0.15)
				)
				(justify left bottom mirror)
			)
		)
		(property "Datasheet" "https://product.tdk.com/en/search/capacitor/ceramic/mlcc/info?part_no=C1005X5R1E474M050BB"
			(at 0 0 270)
			(layer "F.Fab")
			(hide yes)
			(effects
				(font
					(size 1.27 1.27)
					(thickness 0.15)
				)
			)
		)
		(property "Description" "SMD Multilayer Ceramic Capacitor, 0.47 µF, 25 V, 0402 [1005 Metric], ± 20%, X5R, C"
			(at 0 0 270)
			(layer "F.Fab")
			(hide yes)
			(effects
				(font
					(size 1.27 1.27)
					(thickness 0.15)
				)
			)
		)
		(property "Author" "Antmicro"
			(at -36.1 222.15 0)
			(layer "B.Fab")
			(hide yes)
			(effects
				(font
					(size 1 1)
					(thickness 0.15)
				)
				(justify mirror)
			)
		)
		(property "Dielectric" ""
			(at -36.1 222.15 0)
			(layer "B.Fab")
			(hide yes)
			(effects
				(font
					(size 1 1)
					(thickness 0.15)
				)
				(justify mirror)
			)
		)
		(property "License" "Apache-2.0"
			(at -36.1 222.15 0)
			(layer "B.Fab")
			(hide yes)
			(effects
				(font
					(size 1 1)
					(thickness 0.15)
				)
				(justify mirror)
			)
		)
		(property "MPN" "C1005X5R1E474M050BB"
			(at -36.1 222.15 0)
			(layer "B.Fab")
			(hide yes)
			(effects
				(font
					(size 1 1)
					(thickness 0.15)
				)
				(justify mirror)
			)
		)
		(property "Manufacturer" "TDK"
			(at -36.1 222.15 0)
			(layer "B.Fab")
			(hide yes)
			(effects
				(font
					(size 1 1)
					(thickness 0.15)
				)
				(justify mirror)
			)
		)
		(property "Val" "470n"
			(at -36.1 222.15 0)
			(layer "B.Fab")
			(hide yes)
			(effects
				(font
					(size 1 1)
					(thickness 0.15)
				)
				(justify mirror)
			)
		)
		(property "Voltage" ""
			(at -36.1 222.15 0)
			(layer "B.Fab")
			(hide yes)
			(effects
				(font
					(size 1 1)
					(thickness 0.15)
				)
				(justify mirror)
			)
		)
		(property "DNP" ""
			(at 0 0 270)
			(unlocked yes)
			(layer "B.Fab")
			(hide yes)
			(effects
				(font
					(size 1 1)
					(thickness 0.15)
				)
				(justify mirror)
			)
		)
		(sheetname "/FPGA banks 34-35 & CFG/")
		(sheetfile "fpga-banks-34-25-cfg.kicad_sch")
		(attr smd)
		(fp_rect
			(start -0.925 0.47)
			(end 0.925 -0.47)
			(stroke
				(width 0.05)
				(type default)
			)
			(fill no)
			(layer "B.CrtYd")
		)
		(fp_line
			(start -0.494 0.25)
			(end 0.504 0.25)
			(stroke
				(width 0.15)
				(type solid)
			)
			(layer "B.Fab")
		)
		(fp_line
			(start 0.504 0.25)
			(end 0.504 -0.248)
			(stroke
				(width 0.15)
				(type solid)
			)
			(layer "B.Fab")
		)
		(fp_line
			(start -0.494 -0.248)
			(end -0.494 0.25)
			(stroke
				(width 0.15)
				(type solid)
			)
			(layer "B.Fab")
		)
		(fp_line
			(start 0.504 -0.248)
			(end -0.494 -0.248)
			(stroke
				(width 0.15)
				(type solid)
			)
			(layer "B.Fab")
		)
		(pad "1" smd roundrect
			(at -0.48 0 270)
			(size 0.59 0.64)
			(layers "B.Cu" "B.Mask" "B.Paste")
			(roundrect_rratio 0.25)
			(net 1 "GND")
			(pintype "passive")
		)
		(pad "2" smd roundrect
			(at 0.48 0 270)
			(size 0.59 0.64)
			(layers "B.Cu" "B.Mask" "B.Paste")
			(roundrect_rratio 0.25)
			(net 3 "VCC1V35")
			(pintype "passive")
		)
	)
)
